# T6G (Grand Teton) — schematic netlist excerpt (pin names and nets, part order shuffled) for the footprints in the layout excerpt that follows; sources: Cadence DE-HDL packaged netlist, KiCad conversion of 04192023_DAF0TMB3IC0_F0TG_MB_C_brd_V02_OCP.brd

R1449  Q_RES  10K 5% CHIP  pkg 0402LF  page 259 : A = P3V3_AUX ; B = PWRGD_P12V_MEM_CPU1_EN_N
R6011  Q_RES  0 5% CHIP  pkg 0402LF  page 150 : A = SGPIO_SCM_LD_<0> ; B = SGPIO_SCM_LD_R_<0>

(kicad_pcb
	(version 20260206)
	(generator "pcbnew")
	(generator_version "10.0")
	(general
		(thickness 1.6)
		(legacy_teardrops no)
	)
	(paper "A4")
	(title_block
		(title "04192023_DAF0TMB3IC0_F0TG_MB_C_brd_V02_OCP.brd")
		(comment 1 "Grand Teton / footprints 4637-4638 of 8354")
	)
	(layers
		(0 "F.Cu" signal "TOP")
		(4 "In1.Cu" signal "GND")
		(6 "In2.Cu" signal "IN1")
		(8 "In3.Cu" signal "GND1")
		(10 "In4.Cu" signal "IN2")
		(12 "In5.Cu" signal "GND2")
		(14 "In6.Cu" signal "IN3")
		(16 "In7.Cu" signal "GND3")
		(18 "In8.Cu" signal "VCC")
		(20 "In9.Cu" signal "VCC1")
		(22 "In10.Cu" signal "GND4")
		(24 "In11.Cu" signal "IN4")
		(26 "In12.Cu" signal "GND5")
		(28 "In13.Cu" signal "IN5")
		(30 "In14.Cu" signal "GND6")
		(32 "In15.Cu" signal "IN6")
		(34 "In16.Cu" signal "GND7")
		(2 "B.Cu" signal "BOTTOM")
		(9 "F.Adhes" user "F.Adhesive")
		(11 "B.Adhes" user "B.Adhesive")
		(13 "F.Paste" user "Package Geometry/Pastemask Top")
		(15 "B.Paste" user "Package Geometry/Pastemask Bottom")
		(5 "F.SilkS" user "Ref Des/Silkscreen Top")
		(7 "B.SilkS" user "Ref Des/Silkscreen Bottom")
		(1 "F.Mask" user "Board Geometry/Soldermask Top")
		(3 "B.Mask" user "Board Geometry/Soldermask Bottom")
		(17 "Dwgs.User" user "User.Drawings")
		(19 "Cmts.User" user "User.Comments")
		(21 "Eco1.User" user "User.Eco1")
		(23 "Eco2.User" user "User.Eco2")
		(25 "Edge.Cuts" user "Board Geometry/Outline")
		(27 "Margin" user)
		(31 "F.CrtYd" user "Package Geometry/Place Bound Top")
		(29 "B.CrtYd" user "Package Geometry/Place Bound Bottom")
		(35 "F.Fab" user "Ref Des/Assembly Top")
		(33 "B.Fab" user "Ref Des/Assembly Bottom")
	)
	(footprint ""
		(layer "F.Cu")
		(at 171.577 -100.294948 -90)
		(property "Reference" "R6011"
			(at 0 0 270)
			(layer "F.SilkS")
			(hide yes)
			(effects
				(font
					(size 1.27 1.27)
				)
			)
		)
		(property "Value" ""
			(at 0 0 270)
			(layer "F.Fab")
			(effects
				(font
					(size 1.27 1.27)
				)
			)
		)
		(duplicate_pad_numbers_are_jumpers no)
		(fp_line
			(start -0.7874 0.4064)
			(end -0.7874 -0.4064)
			(stroke
				(width 0.1524)
				(type default)
			)
			(layer "F.SilkS")
		)
		(fp_line
			(start 0.7874 0.4064)
			(end -0.7874 0.4064)
			(stroke
				(width 0.1524)
				(type default)
			)
			(layer "F.SilkS")
		)
		(fp_line
			(start -0.7874 -0.4064)
			(end 0.7874 -0.4064)
			(stroke
				(width 0.1524)
				(type default)
			)
			(layer "F.SilkS")
		)
		(fp_line
			(start 0.7874 -0.4064)
			(end 0.7874 0.4064)
			(stroke
				(width 0.1524)
				(type default)
			)
			(layer "F.SilkS")
		)
		(fp_line
			(start -0.67945 0.3048)
			(end -0.67945 -0.305054)
			(stroke
				(width 0.1)
				(type default)
			)
			(layer "F.Fab")
		)
		(fp_line
			(start -0.12065 0.3048)
			(end -0.67945 0.3048)
			(stroke
				(width 0.1)
				(type default)
			)
			(layer "F.Fab")
		)
		(fp_line
			(start 0.120396 0.3048)
			(end 0.120396 0.2794)
			(stroke
				(width 0.1)
				(type default)
			)
			(layer "F.Fab")
		)
		(fp_line
			(start 0.67945 0.3048)
			(end 0.120396 0.3048)
			(stroke
				(width 0.1)
				(type default)
			)
			(layer "F.Fab")
		)
		(fp_line
			(start -0.12065 0.2794)
			(end -0.12065 0.3048)
			(stroke
				(width 0.1)
				(type default)
			)
			(layer "F.Fab")
		)
		(fp_line
			(start 0.120396 0.2794)
			(end -0.12065 0.2794)
			(stroke
				(width 0.1)
				(type default)
			)
			(layer "F.Fab")
		)
		(fp_line
			(start -0.12065 -0.2794)
			(end 0.12065 -0.2794)
			(stroke
				(width 0.1)
				(type default)
			)
			(layer "F.Fab")
		)
		(fp_line
			(start 0.12065 -0.2794)
			(end 0.12065 -0.3048)
			(stroke
				(width 0.1)
				(type default)
			)
			(layer "F.Fab")
		)
		(fp_line
			(start 0.12065 -0.3048)
			(end 0.67945 -0.3048)
			(stroke
				(width 0.1)
				(type default)
			)
			(layer "F.Fab")
		)
		(fp_line
			(start 0.67945 -0.3048)
			(end 0.67945 0.3048)
			(stroke
				(width 0.1)
				(type default)
			)
			(layer "F.Fab")
		)
		(fp_line
			(start -0.67945 -0.305054)
			(end -0.12065 -0.305054)
			(stroke
				(width 0.1)
				(type default)
			)
			(layer "F.Fab")
		)
		(fp_line
			(start -0.12065 -0.305054)
			(end -0.12065 -0.2794)
			(stroke
				(width 0.1)
				(type default)
			)
			(layer "F.Fab")
		)
		(pad "1" smd circle
			(at -0.40005 0 270)
			(size 0 0)
			(layers "F.Cu" "F.Mask" "F.Paste")
			(net "SGPIO_SCM_LD_<0>")
		)
		(pad "2" smd circle
			(at 0.40005 0 270)
			(size 0 0)
			(layers "F.Cu" "F.Mask" "F.Paste")
			(net "SGPIO_SCM_LD_R_<0>")
		)
	)
	(footprint ""
		(layer "F.Cu")
		(at 105.659936 -119.479568 90)
		(property "Reference" "R1449"
			(at 0 0 90)
			(layer "F.SilkS")
			(hide yes)
			(effects
				(font
					(size 1.27 1.27)
				)
			)
		)
		(property "Value" ""
			(at 0 0 90)
			(layer "F.Fab")
			(effects
				(font
					(size 1.27 1.27)
				)
			)
		)
		(duplicate_pad_numbers_are_jumpers no)
		(fp_line
			(start 0.7874 -0.4064)
			(end 0.7874 0.4064)
			(stroke
				(width 0.1524)
				(type default)
			)
			(layer "F.SilkS")
		)
		(fp_line
			(start -0.7874 -0.4064)
			(end 0.7874 -0.4064)
			(stroke
				(width 0.1524)
				(type default)
			)
			(layer "F.SilkS")
		)
		(fp_line
			(start 0.7874 0.4064)
			(end -0.7874 0.4064)
			(stroke
				(width 0.1524)
				(type default)
			)
			(layer "F.SilkS")
		)
		(fp_line
			(start -0.7874 0.4064)
			(end -0.7874 -0.4064)
			(stroke
				(width 0.1524)
				(type default)
			)
			(layer "F.SilkS")
		)
		(fp_line
			(start -0.12065 -0.305054)
			(end -0.12065 -0.2794)
			(stroke
				(width 0.1)
				(type default)
			)
			(layer "F.Fab")
		)
		(fp_line
			(start -0.67945 -0.305054)
			(end -0.12065 -0.305054)
			(stroke
				(width 0.1)
				(type default)
			)
			(layer "F.Fab")
		)
		(fp_line
			(start 0.67945 -0.3048)
			(end 0.67945 0.3048)
			(stroke
				(width 0.1)
				(type default)
			)
			(layer "F.Fab")
		)
		(fp_line
			(start 0.12065 -0.3048)
			(end 0.67945 -0.3048)
			(stroke
				(width 0.1)
				(type default)
			)
			(layer "F.Fab")
		)
		(fp_line
			(start 0.12065 -0.2794)
			(end 0.12065 -0.3048)
			(stroke
				(width 0.1)
				(type default)
			)
			(layer "F.Fab")
		)
		(fp_line
			(start -0.12065 -0.2794)
			(end 0.12065 -0.2794)
			(stroke
				(width 0.1)
				(type default)
			)
			(layer "F.Fab")
		)
		(fp_line
			(start 0.120396 0.2794)
			(end -0.12065 0.2794)
			(stroke
				(width 0.1)
				(type default)
			)
			(layer "F.Fab")
		)
		(fp_line
			(start -0.12065 0.2794)
			(end -0.12065 0.3048)
			(stroke
				(width 0.1)
				(type default)
			)
			(layer "F.Fab")
		)
		(fp_line
			(start 0.67945 0.3048)
			(end 0.120396 0.3048)
			(stroke
				(width 0.1)
				(type default)
			)
			(layer "F.Fab")
		)
		(fp_line
			(start 0.120396 0.3048)
			(end 0.120396 0.2794)
			(stroke
				(width 0.1)
				(type default)
			)
			(layer "F.Fab")
		)
		(fp_line
			(start -0.12065 0.3048)
			(end -0.67945 0.3048)
			(stroke
				(width 0.1)
				(type default)
			)
			(layer "F.Fab")
		)
		(fp_line
			(start -0.67945 0.3048)
			(end -0.67945 -0.305054)
			(stroke
				(width 0.1)
				(type default)
			)
			(layer "F.Fab")
		)
		(pad "1" smd circle
			(at -0.40005 0 90)
			(size 0 0)
			(layers "F.Cu" "F.Mask" "F.Paste")
			(net "P3V3_AUX")
		)
		(pad "2" smd circle
			(at 0.40005 0 90)
			(size 0 0)
			(layers "F.Cu" "F.Mask" "F.Paste")
			(net "PWRGD_P12V_MEM_CPU1_EN_N")
		)
	)
)
